# BASEBOARD_FAB2 (Tioga Pass) — schematic netlist excerpt (pin names and nets, part order shuffled) for the footprints in the layout excerpt that follows; sources: Cadence DE-HDL packaged netlist, KiCad conversion of Wiwynn_Tioga_Pass_MB.brd

R9L3  RES  2 1.0% CHIP  pkg 0402  page 100 : A = M_M_CPU_VREF ; B = M_M_VREF
C2N11  CAP_A  1.0UF 6.3V 10% X6S  pkg 0402V  page 132 : A = PVNN_PCH_STBY ; B = GND

(kicad_pcb
	(version 20260206)
	(generator "pcbnew")
	(generator_version "10.0")
	(general
		(thickness 1.6)
		(legacy_teardrops no)
	)
	(paper "A4")
	(title_block
		(title "Wiwynn_Tioga_Pass_MB.brd")
		(comment 1 "Tioga Pass / footprints 3609-3610 of 4770")
	)
	(layers
		(0 "F.Cu" signal "TOP")
		(4 "In1.Cu" signal "L2GND")
		(6 "In2.Cu" signal "L3")
		(8 "In3.Cu" signal "L4GND")
		(10 "In4.Cu" signal "L5")
		(12 "In5.Cu" signal "L6GND")
		(14 "In6.Cu" signal "L7VCC")
		(16 "In7.Cu" signal "L8VCC")
		(18 "In8.Cu" signal "L9GND")
		(20 "In9.Cu" signal "L10")
		(22 "In10.Cu" signal "L11GND")
		(24 "In11.Cu" signal "L12")
		(26 "In12.Cu" signal "L13GND")
		(2 "B.Cu" signal "BOTTOM")
		(9 "F.Adhes" user "F.Adhesive")
		(11 "B.Adhes" user "B.Adhesive")
		(13 "F.Paste" user "Package Geometry/Pastemask Top")
		(15 "B.Paste" user "Package Geometry/Pastemask Bottom")
		(5 "F.SilkS" user "Ref Des/Silkscreen Top")
		(7 "B.SilkS" user "Ref Des/Silkscreen Bottom")
		(1 "F.Mask" user "Board Geometry/Soldermask Top")
		(3 "B.Mask" user "Board Geometry/Soldermask Bottom")
		(17 "Dwgs.User" user "User.Drawings")
		(19 "Cmts.User" user "User.Comments")
		(21 "Eco1.User" user "User.Eco1")
		(23 "Eco2.User" user "User.Eco2")
		(25 "Edge.Cuts" user "Board Geometry/Outline")
		(27 "Margin" user)
		(31 "F.CrtYd" user "Package Geometry/Place Bound Top")
		(29 "B.CrtYd" user "Package Geometry/Place Bound Bottom")
		(35 "F.Fab" user "Ref Des/Assembly Top")
		(33 "B.Fab" user "Ref Des/Assembly Bottom")
	)
	(footprint ""
		(layer "B.Cu")
		(at 390.93775 -107.85475 90)
		(property "Reference" "C2N11"
			(at 0 0 90)
			(layer "B.SilkS")
			(hide yes)
			(effects
				(font
					(size 1.27 1.27)
				)
				(justify mirror)
			)
		)
		(property "Value" ""
			(at 0 0 90)
			(layer "B.Fab")
			(effects
				(font
					(size 1.27 1.27)
				)
				(justify mirror)
			)
		)
		(duplicate_pad_numbers_are_jumpers no)
		(fp_rect
			(start 0.2794 0.9144)
			(end -0.2794 -0.1143)
			(stroke
				(width 0)
				(type default)
			)
			(fill no)
			(layer "B.CrtYd")
		)
		(fp_line
			(start 0.2794 -0.1143)
			(end -0.2794 -0.1143)
			(stroke
				(width 0.1)
				(type default)
			)
			(layer "B.Fab")
		)
		(fp_line
			(start -0.2794 -0.1143)
			(end -0.2794 0.9144)
			(stroke
				(width 0.1)
				(type default)
			)
			(layer "B.Fab")
		)
		(fp_line
			(start 0.2794 0.9144)
			(end 0.2794 -0.1143)
			(stroke
				(width 0.1)
				(type default)
			)
			(layer "B.Fab")
		)
		(fp_line
			(start -0.2794 0.9144)
			(end 0.2794 0.9144)
			(stroke
				(width 0.1)
				(type default)
			)
			(layer "B.Fab")
		)
		(pad "1" smd custom
			(at 0 0)
			(size 0.10414 0.10414)
			(layers "B.Cu" "B.Mask" "B.Paste")
			(net "PVNN_PCH_STBY")
			(options
				(clearance outline)
				(anchor circle)
			)
			(primitives
				(gr_poly
					(pts
						(xy -0.20828 -0.08636) (xy -0.20828 0.08636) (xy -0.08636 0.20828) (xy 0.086614 0.20828) (xy 0.20828 0.086614)
						(xy 0.20828 -0.08636) (xy 0.08636 -0.20828) (xy -0.08636 -0.20828)
					)
					(width 0)
					(fill yes)
				)
			)
		)
		(pad "2" smd custom
			(at 0 0.8001)
			(size 0.10414 0.10414)
			(layers "B.Cu" "B.Mask" "B.Paste")
			(net "GND")
			(options
				(clearance outline)
				(anchor circle)
			)
			(primitives
				(gr_poly
					(pts
						(xy -0.20828 -0.08636) (xy -0.20828 0.08636) (xy -0.08636 0.20828) (xy 0.086614 0.20828) (xy 0.20828 0.086614)
						(xy 0.20828 -0.08636) (xy 0.08636 -0.20828) (xy -0.08636 -0.20828)
					)
					(width 0)
					(fill yes)
				)
			)
		)
		(zone
			(layer "B.Cu")
			(hatch none 0.5)
			(connect_pads
				(clearance 0)
			)
			(min_thickness 0.25)
			(keepout
				(tracks allowed)
				(vias not_allowed)
				(pads allowed)
				(copperpour not_allowed)
				(footprints allowed)
			)
			(placement
				(enabled no)
				(sheetname "")
			)
			(fill
				(thermal_gap 0.5)
				(thermal_bridge_width 0.5)
				(island_removal_mode 0)
			)
			(polygon
				(pts
					(xy 391.1473 -107.94238) (xy 391.5283 -107.94238) (xy 391.5283 -107.76712) (xy 391.1473 -107.766866)
				)
			)
		)
		(zone
			(layer "B.Cu")
			(hatch none 0.5)
			(connect_pads
				(clearance 0)
			)
			(min_thickness 0.25)
			(keepout
				(tracks not_allowed)
				(vias allowed)
				(pads allowed)
				(copperpour not_allowed)
				(footprints allowed)
			)
			(placement
				(enabled no)
				(sheetname "")
			)
			(fill
				(thermal_gap 0.5)
				(thermal_bridge_width 0.5)
				(island_removal_mode 0)
			)
			(polygon
				(pts
					(xy 391.1473 -107.94238) (xy 391.5283 -107.94238) (xy 391.5283 -107.76712) (xy 391.1473 -107.766866)
				)
			)
		)
	)
	(footprint ""
		(layer "B.Cu")
		(at 27.785568 -154.559 180)
		(property "Reference" "R9L3"
			(at 0 0 0)
			(layer "B.SilkS")
			(hide yes)
			(effects
				(font
					(size 1.27 1.27)
				)
				(justify mirror)
			)
		)
		(property "Value" ""
			(at 0 0 0)
			(layer "B.Fab")
			(effects
				(font
					(size 1.27 1.27)
				)
				(justify mirror)
			)
		)
		(duplicate_pad_numbers_are_jumpers no)
		(fp_poly
			(pts
				(xy 0.2794 -0.1016) (xy -0.2794 -0.1016) (xy -0.2794 0.9906) (xy 0.2794 0.9906)
			)
			(stroke
				(width 0)
				(type default)
			)
			(fill no)
			(layer "B.CrtYd")
		)
		(fp_line
			(start 0.2794 0.9906)
			(end -0.2794 0.9906)
			(stroke
				(width 0.1)
				(type default)
			)
			(layer "B.Fab")
		)
		(fp_line
			(start 0.2794 -0.1016)
			(end 0.2794 0.9906)
			(stroke
				(width 0.1)
				(type default)
			)
			(layer "B.Fab")
		)
		(fp_line
			(start -0.2794 0.9906)
			(end -0.2794 -0.1016)
			(stroke
				(width 0.1)
				(type default)
			)
			(layer "B.Fab")
		)
		(fp_line
			(start -0.2794 -0.1016)
			(end 0.2794 -0.1016)
			(stroke
				(width 0.1)
				(type default)
			)
			(layer "B.Fab")
		)
		(pad "1" smd rect
			(at 0 0)
			(size 0.508 0.508)
			(layers "B.Cu" "B.Mask" "B.Paste")
			(net "M_M_CPU_VREF")
		)
		(pad "2" smd rect
			(at 0 0.889)
			(size 0.508 0.508)
			(layers "B.Cu" "B.Mask" "B.Paste")
			(net "M_M_VREF")
		)
		(zone
			(layer "B.Cu")
			(hatch none 0.5)
			(connect_pads
				(clearance 0)
			)
			(min_thickness 0.25)
			(keepout
				(tracks not_allowed)
				(vias allowed)
				(pads allowed)
				(copperpour not_allowed)
				(footprints allowed)
			)
			(placement
				(enabled no)
				(sheetname "")
			)
			(fill
				(thermal_gap 0.5)
				(thermal_bridge_width 0.5)
				(island_removal_mode 0)
			)
			(polygon
				(pts
					(xy 27.531568 -155.194) (xy 28.039568 -155.194) (xy 28.039568 -154.813) (xy 27.531568 -154.813)
				)
			)
		)
		(zone
			(layer "B.Cu")
			(hatch none 0.5)
			(connect_pads
				(clearance 0)
			)
			(min_thickness 0.25)
			(keepout
				(tracks allowed)
				(vias not_allowed)
				(pads allowed)
				(copperpour not_allowed)
				(footprints allowed)
			)
			(placement
				(enabled no)
				(sheetname "")
			)
			(fill
				(thermal_gap 0.5)
				(thermal_bridge_width 0.5)
				(island_removal_mode 0)
			)
			(polygon
				(pts
					(xy 27.531568 -154.813) (xy 28.039568 -154.813) (xy 28.039568 -155.194) (xy 27.531568 -155.194)
				)
			)
		)
	)
)
